(kicad_pcb
	(version 20260206)
	(generator "pcbnew")
	(generator_version "10.0")
	(general
		(thickness 1.6)
		(legacy_teardrops no)
	)
	(paper "A4")
	(title_block
		(title "01162023_DA0F0TEBIF0_F0T_Expander_BD_F_brd_V02_OCP.brd")
		(comment 1 "Grand Teton / footprints 9097-9104 of 9728")
	)
	(layers
		(0 "F.Cu" signal "TOP")
		(4 "In1.Cu" signal "GND")
		(6 "In2.Cu" signal "VCC")
		(8 "In3.Cu" signal "VCC1")
		(10 "In4.Cu" signal "GND1")
		(12 "In5.Cu" signal "IN1")
		(14 "In6.Cu" signal "GND2")
		(16 "In7.Cu" signal "IN2")
		(18 "In8.Cu" signal "GND3")
		(20 "In9.Cu" signal "IN3")
		(22 "In10.Cu" signal "GND4")
		(24 "In11.Cu" signal "IN4")
		(26 "In12.Cu" signal "GND5")
		(28 "In13.Cu" signal "IN5")
		(30 "In14.Cu" signal "GND6")
		(32 "In15.Cu" signal "IN6")
		(34 "In16.Cu" signal "GND7")
		(2 "B.Cu" signal "BOTTOM")
		(9 "F.Adhes" user "F.Adhesive")
		(11 "B.Adhes" user "B.Adhesive")
		(13 "F.Paste" user "Package Geometry/Pastemask Top")
		(15 "B.Paste" user "Package Geometry/Pastemask Bottom")
		(5 "F.SilkS" user "Ref Des/Silkscreen Top")
		(7 "B.SilkS" user "Ref Des/Silkscreen Bottom")
		(1 "F.Mask" user "Board Geometry/Soldermask Top")
		(3 "B.Mask" user "Board Geometry/Soldermask Bottom")
		(17 "Dwgs.User" user "User.Drawings")
		(19 "Cmts.User" user "User.Comments")
		(21 "Eco1.User" user "User.Eco1")
		(23 "Eco2.User" user "User.Eco2")
		(25 "Edge.Cuts" user "Board Geometry/Outline")
		(27 "Margin" user)
		(31 "F.CrtYd" user "Package Geometry/Place Bound Top")
		(29 "B.CrtYd" user "Package Geometry/Place Bound Bottom")
		(35 "F.Fab" user "Ref Des/Assembly Top")
		(33 "B.Fab" user "Ref Des/Assembly Bottom")
	)
	(footprint ""
		(layer "B.Cu")
		(at 236.546644 -231.225598 -90)
		(property "Reference" "R4529"
			(at 0 0 90)
			(layer "B.SilkS")
			(hide yes)
			(effects
				(font
					(size 1.27 1.27)
				)
				(justify mirror)
			)
		)
		(property "Value" ""
			(at 0 0 90)
			(layer "B.Fab")
			(effects
				(font
					(size 1.27 1.27)
				)
				(justify mirror)
			)
		)
		(duplicate_pad_numbers_are_jumpers no)
		(fp_line
			(start -0.7874 0.4064)
			(end 0.7874 0.4064)
			(stroke
				(width 0.1524)
				(type default)
			)
			(layer "B.SilkS")
		)
		(fp_line
			(start 0.7874 0.4064)
			(end 0.7874 -0.4064)
			(stroke
				(width 0.1524)
				(type default)
			)
			(layer "B.SilkS")
		)
		(fp_line
			(start -0.7874 -0.4064)
			(end -0.7874 0.4064)
			(stroke
				(width 0.1524)
				(type default)
			)
			(layer "B.SilkS")
		)
		(fp_line
			(start 0.7874 -0.4064)
			(end -0.7874 -0.4064)
			(stroke
				(width 0.1524)
				(type default)
			)
			(layer "B.SilkS")
		)
		(fp_line
			(start -0.67945 0.3048)
			(end -0.120396 0.3048)
			(stroke
				(width 0.1)
				(type default)
			)
			(layer "B.Fab")
		)
		(fp_line
			(start -0.120396 0.3048)
			(end -0.120396 0.2794)
			(stroke
				(width 0.1)
				(type default)
			)
			(layer "B.Fab")
		)
		(fp_line
			(start 0.12065 0.3048)
			(end 0.67945 0.3048)
			(stroke
				(width 0.1)
				(type default)
			)
			(layer "B.Fab")
		)
		(fp_line
			(start 0.67945 0.3048)
			(end 0.67945 -0.305054)
			(stroke
				(width 0.1)
				(type default)
			)
			(layer "B.Fab")
		)
		(fp_line
			(start -0.120396 0.2794)
			(end 0.12065 0.2794)
			(stroke
				(width 0.1)
				(type default)
			)
			(layer "B.Fab")
		)
		(fp_line
			(start 0.12065 0.2794)
			(end 0.12065 0.3048)
			(stroke
				(width 0.1)
				(type default)
			)
			(layer "B.Fab")
		)
		(fp_line
			(start -0.12065 -0.2794)
			(end -0.12065 -0.3048)
			(stroke
				(width 0.1)
				(type default)
			)
			(layer "B.Fab")
		)
		(fp_line
			(start 0.12065 -0.2794)
			(end -0.12065 -0.2794)
			(stroke
				(width 0.1)
				(type default)
			)
			(layer "B.Fab")
		)
		(fp_line
			(start -0.67945 -0.3048)
			(end -0.67945 0.3048)
			(stroke
				(width 0.1)
				(type default)
			)
			(layer "B.Fab")
		)
		(fp_line
			(start -0.12065 -0.3048)
			(end -0.67945 -0.3048)
			(stroke
				(width 0.1)
				(type default)
			)
			(layer "B.Fab")
		)
		(fp_line
			(start 0.12065 -0.305054)
			(end 0.12065 -0.2794)
			(stroke
				(width 0.1)
				(type default)
			)
			(layer "B.Fab")
		)
		(fp_line
			(start 0.67945 -0.305054)
			(end 0.12065 -0.305054)
			(stroke
				(width 0.1)
				(type default)
			)
			(layer "B.Fab")
		)
		(pad "1" smd circle
			(at 0.40005 0 90)
			(size 0 0)
			(layers "B.Cu" "B.Mask" "B.Paste")
			(net "SSD15_PWRDIS_BIC")
		)
		(pad "2" smd circle
			(at -0.40005 0 90)
			(size 0 0)
			(layers "B.Cu" "B.Mask" "B.Paste")
			(net "SSD15_PWRDIS_BIC_R")
		)
	)
	(footprint ""
		(layer "B.Cu")
		(at 364.322106 -308.677818 90)
		(property "Reference" "C4377"
			(at 0 0 90)
			(layer "B.SilkS")
			(hide yes)
			(effects
				(font
					(size 1.27 1.27)
				)
				(justify mirror)
			)
		)
		(property "Value" ""
			(at 0 0 90)
			(layer "B.Fab")
			(effects
				(font
					(size 1.27 1.27)
				)
				(justify mirror)
			)
		)
		(duplicate_pad_numbers_are_jumpers no)
		(fp_line
			(start 0.299974 -0.150114)
			(end -0.299974 -0.150114)
			(stroke
				(width 0.1)
				(type default)
			)
			(layer "B.Fab")
		)
		(fp_line
			(start -0.299974 -0.150114)
			(end -0.299974 0.150114)
			(stroke
				(width 0.1)
				(type default)
			)
			(layer "B.Fab")
		)
		(fp_line
			(start 0.299974 0.150114)
			(end 0.299974 -0.150114)
			(stroke
				(width 0.1)
				(type default)
			)
			(layer "B.Fab")
		)
		(fp_line
			(start -0.299974 0.150114)
			(end 0.299974 0.150114)
			(stroke
				(width 0.1)
				(type default)
			)
			(layer "B.Fab")
		)
		(pad "1" smd rect
			(at 0.2667 0 270)
			(size 0.3048 0.381)
			(layers "B.Cu" "B.Mask" "B.Paste")
			(net "P0V8_PEX3")
		)
		(pad "2" smd rect
			(at -0.2667 0 270)
			(size 0.3048 0.381)
			(layers "B.Cu" "B.Mask" "B.Paste")
			(net "GND")
		)
	)
	(footprint ""
		(layer "B.Cu")
		(at 454.907396 -251.35586)
		(property "Reference" "R6583"
			(at 0 0 0)
			(layer "B.SilkS")
			(hide yes)
			(effects
				(font
					(size 1.27 1.27)
				)
				(justify mirror)
			)
		)
		(property "Value" ""
			(at 0 0 0)
			(layer "B.Fab")
			(effects
				(font
					(size 1.27 1.27)
				)
				(justify mirror)
			)
		)
		(duplicate_pad_numbers_are_jumpers no)
		(fp_line
			(start -0.7874 -0.4064)
			(end -0.7874 0.4064)
			(stroke
				(width 0.1524)
				(type default)
			)
			(layer "B.SilkS")
		)
		(fp_line
			(start -0.7874 0.4064)
			(end 0.7874 0.4064)
			(stroke
				(width 0.1524)
				(type default)
			)
			(layer "B.SilkS")
		)
		(fp_line
			(start 0.7874 -0.4064)
			(end -0.7874 -0.4064)
			(stroke
				(width 0.1524)
				(type default)
			)
			(layer "B.SilkS")
		)
		(fp_line
			(start 0.7874 0.4064)
			(end 0.7874 -0.4064)
			(stroke
				(width 0.1524)
				(type default)
			)
			(layer "B.SilkS")
		)
		(fp_line
			(start -0.67945 -0.3048)
			(end -0.67945 0.3048)
			(stroke
				(width 0.1)
				(type default)
			)
			(layer "B.Fab")
		)
		(fp_line
			(start -0.67945 0.3048)
			(end -0.120396 0.3048)
			(stroke
				(width 0.1)
				(type default)
			)
			(layer "B.Fab")
		)
		(fp_line
			(start -0.12065 -0.3048)
			(end -0.67945 -0.3048)
			(stroke
				(width 0.1)
				(type default)
			)
			(layer "B.Fab")
		)
		(fp_line
			(start -0.12065 -0.2794)
			(end -0.12065 -0.3048)
			(stroke
				(width 0.1)
				(type default)
			)
			(layer "B.Fab")
		)
		(fp_line
			(start -0.120396 0.2794)
			(end 0.12065 0.2794)
			(stroke
				(width 0.1)
				(type default)
			)
			(layer "B.Fab")
		)
		(fp_line
			(start -0.120396 0.3048)
			(end -0.120396 0.2794)
			(stroke
				(width 0.1)
				(type default)
			)
			(layer "B.Fab")
		)
		(fp_line
			(start 0.12065 -0.305054)
			(end 0.12065 -0.2794)
			(stroke
				(width 0.1)
				(type default)
			)
			(layer "B.Fab")
		)
		(fp_line
			(start 0.12065 -0.2794)
			(end -0.12065 -0.2794)
			(stroke
				(width 0.1)
				(type default)
			)
			(layer "B.Fab")
		)
		(fp_line
			(start 0.12065 0.2794)
			(end 0.12065 0.3048)
			(stroke
				(width 0.1)
				(type default)
			)
			(layer "B.Fab")
		)
		(fp_line
			(start 0.12065 0.3048)
			(end 0.67945 0.3048)
			(stroke
				(width 0.1)
				(type default)
			)
			(layer "B.Fab")
		)
		(fp_line
			(start 0.67945 -0.305054)
			(end 0.12065 -0.305054)
			(stroke
				(width 0.1)
				(type default)
			)
			(layer "B.Fab")
		)
		(fp_line
			(start 0.67945 0.3048)
			(end 0.67945 -0.305054)
			(stroke
				(width 0.1)
				(type default)
			)
			(layer "B.Fab")
		)
		(pad "1" smd circle
			(at 0.40005 0 180)
			(size 0 0)
			(layers "B.Cu" "B.Mask" "B.Paste")
			(net "P3V3_AUX")
		)
		(pad "2" smd circle
			(at -0.40005 0 180)
			(size 0 0)
			(layers "B.Cu" "B.Mask" "B.Paste")
			(net "PEX3_P1V8_PLL_EN")
		)
	)
	(footprint ""
		(layer "B.Cu")
		(at 60.452 -296.3926 180)
		(property "Reference" "C1128"
			(at 0 0 0)
			(layer "B.SilkS")
			(hide yes)
			(effects
				(font
					(size 1.27 1.27)
				)
				(justify mirror)
			)
		)
		(property "Value" ""
			(at 0 0 0)
			(layer "B.Fab")
			(effects
				(font
					(size 1.27 1.27)
				)
				(justify mirror)
			)
		)
		(duplicate_pad_numbers_are_jumpers no)
		(fp_line
			(start 0.299974 0.150114)
			(end 0.299974 -0.150114)
			(stroke
				(width 0.1)
				(type default)
			)
			(layer "B.Fab")
		)
		(fp_line
			(start 0.299974 -0.150114)
			(end -0.299974 -0.150114)
			(stroke
				(width 0.1)
				(type default)
			)
			(layer "B.Fab")
		)
		(fp_line
			(start -0.299974 0.150114)
			(end 0.299974 0.150114)
			(stroke
				(width 0.1)
				(type default)
			)
			(layer "B.Fab")
		)
		(fp_line
			(start -0.299974 -0.150114)
			(end -0.299974 0.150114)
			(stroke
				(width 0.1)
				(type default)
			)
			(layer "B.Fab")
		)
		(pad "1" smd rect
			(at 0.2667 0)
			(size 0.3048 0.381)
			(layers "B.Cu" "B.Mask" "B.Paste")
			(net "P0V8_PEX0")
		)
		(pad "2" smd rect
			(at -0.2667 0)
			(size 0.3048 0.381)
			(layers "B.Cu" "B.Mask" "B.Paste")
			(net "GND")
		)
	)
	(footprint ""
		(layer "B.Cu")
		(at 281.755342 -153.0096)
		(property "Reference" "R223"
			(at 0 0 0)
			(layer "B.SilkS")
			(hide yes)
			(effects
				(font
					(size 1.27 1.27)
				)
				(justify mirror)
			)
		)
		(property "Value" ""
			(at 0 0 0)
			(layer "B.Fab")
			(effects
				(font
					(size 1.27 1.27)
				)
				(justify mirror)
			)
		)
		(duplicate_pad_numbers_are_jumpers no)
		(fp_line
			(start -0.7874 -0.4064)
			(end -0.7874 0.4064)
			(stroke
				(width 0.1524)
				(type default)
			)
			(layer "B.SilkS")
		)
		(fp_line
			(start -0.7874 0.4064)
			(end 0.7874 0.4064)
			(stroke
				(width 0.1524)
				(type default)
			)
			(layer "B.SilkS")
		)
		(fp_line
			(start 0.7874 -0.4064)
			(end -0.7874 -0.4064)
			(stroke
				(width 0.1524)
				(type default)
			)
			(layer "B.SilkS")
		)
		(fp_line
			(start 0.7874 0.4064)
			(end 0.7874 -0.4064)
			(stroke
				(width 0.1524)
				(type default)
			)
			(layer "B.SilkS")
		)
		(fp_line
			(start -0.67945 -0.3048)
			(end -0.67945 0.3048)
			(stroke
				(width 0.1)
				(type default)
			)
			(layer "B.Fab")
		)
		(fp_line
			(start -0.67945 0.3048)
			(end -0.120396 0.3048)
			(stroke
				(width 0.1)
				(type default)
			)
			(layer "B.Fab")
		)
		(fp_line
			(start -0.12065 -0.3048)
			(end -0.67945 -0.3048)
			(stroke
				(width 0.1)
				(type default)
			)
			(layer "B.Fab")
		)
		(fp_line
			(start -0.12065 -0.2794)
			(end -0.12065 -0.3048)
			(stroke
				(width 0.1)
				(type default)
			)
			(layer "B.Fab")
		)
		(fp_line
			(start -0.120396 0.2794)
			(end 0.12065 0.2794)
			(stroke
				(width 0.1)
				(type default)
			)
			(layer "B.Fab")
		)
		(fp_line
			(start -0.120396 0.3048)
			(end -0.120396 0.2794)
			(stroke
				(width 0.1)
				(type default)
			)
			(layer "B.Fab")
		)
		(fp_line
			(start 0.12065 -0.305054)
			(end 0.12065 -0.2794)
			(stroke
				(width 0.1)
				(type default)
			)
			(layer "B.Fab")
		)
		(fp_line
			(start 0.12065 -0.2794)
			(end -0.12065 -0.2794)
			(stroke
				(width 0.1)
				(type default)
			)
			(layer "B.Fab")
		)
		(fp_line
			(start 0.12065 0.2794)
			(end 0.12065 0.3048)
			(stroke
				(width 0.1)
				(type default)
			)
			(layer "B.Fab")
		)
		(fp_line
			(start 0.12065 0.3048)
			(end 0.67945 0.3048)
			(stroke
				(width 0.1)
				(type default)
			)
			(layer "B.Fab")
		)
		(fp_line
			(start 0.67945 -0.305054)
			(end 0.12065 -0.305054)
			(stroke
				(width 0.1)
				(type default)
			)
			(layer "B.Fab")
		)
		(fp_line
			(start 0.67945 0.3048)
			(end 0.67945 -0.305054)
			(stroke
				(width 0.1)
				(type default)
			)
			(layer "B.Fab")
		)
		(pad "1" smd circle
			(at 0.40005 0 180)
			(size 0 0)
			(layers "B.Cu" "B.Mask" "B.Paste")
			(net "NCSI_NIC4_TXD1")
		)
		(pad "2" smd circle
			(at -0.40005 0 180)
			(size 0 0)
			(layers "B.Cu" "B.Mask" "B.Paste")
			(net "GND")
		)
	)
	(footprint ""
		(layer "B.Cu")
		(at 245.505732 -366.896396 180)
		(property "Reference" "PR6608"
			(at 0 0 0)
			(layer "B.SilkS")
			(hide yes)
			(effects
				(font
					(size 1.27 1.27)
				)
				(justify mirror)
			)
		)
		(property "Value" ""
			(at 0 0 0)
			(layer "B.Fab")
			(effects
				(font
					(size 1.27 1.27)
				)
				(justify mirror)
			)
		)
		(duplicate_pad_numbers_are_jumpers no)
		(fp_line
			(start 0.7874 0.4064)
			(end 0.7874 -0.4064)
			(stroke
				(width 0.1524)
				(type default)
			)
			(layer "B.SilkS")
		)
		(fp_line
			(start 0.7874 -0.4064)
			(end -0.7874 -0.4064)
			(stroke
				(width 0.1524)
				(type default)
			)
			(layer "B.SilkS")
		)
		(fp_line
			(start -0.7874 0.4064)
			(end 0.7874 0.4064)
			(stroke
				(width 0.1524)
				(type default)
			)
			(layer "B.SilkS")
		)
		(fp_line
			(start -0.7874 -0.4064)
			(end -0.7874 0.4064)
			(stroke
				(width 0.1524)
				(type default)
			)
			(layer "B.SilkS")
		)
		(fp_line
			(start 0.67945 0.3048)
			(end 0.67945 -0.305054)
			(stroke
				(width 0.1)
				(type default)
			)
			(layer "B.Fab")
		)
		(fp_line
			(start 0.67945 -0.305054)
			(end 0.12065 -0.305054)
			(stroke
				(width 0.1)
				(type default)
			)
			(layer "B.Fab")
		)
		(fp_line
			(start 0.12065 0.3048)
			(end 0.67945 0.3048)
			(stroke
				(width 0.1)
				(type default)
			)
			(layer "B.Fab")
		)
		(fp_line
			(start 0.12065 0.2794)
			(end 0.12065 0.3048)
			(stroke
				(width 0.1)
				(type default)
			)
			(layer "B.Fab")
		)
		(fp_line
			(start 0.12065 -0.2794)
			(end -0.12065 -0.2794)
			(stroke
				(width 0.1)
				(type default)
			)
			(layer "B.Fab")
		)
		(fp_line
			(start 0.12065 -0.305054)
			(end 0.12065 -0.2794)
			(stroke
				(width 0.1)
				(type default)
			)
			(layer "B.Fab")
		)
		(fp_line
			(start -0.120396 0.3048)
			(end -0.120396 0.2794)
			(stroke
				(width 0.1)
				(type default)
			)
			(layer "B.Fab")
		)
		(fp_line
			(start -0.120396 0.2794)
			(end 0.12065 0.2794)
			(stroke
				(width 0.1)
				(type default)
			)
			(layer "B.Fab")
		)
		(fp_line
			(start -0.12065 -0.2794)
			(end -0.12065 -0.3048)
			(stroke
				(width 0.1)
				(type default)
			)
			(layer "B.Fab")
		)
		(fp_line
			(start -0.12065 -0.3048)
			(end -0.67945 -0.3048)
			(stroke
				(width 0.1)
				(type default)
			)
			(layer "B.Fab")
		)
		(fp_line
			(start -0.67945 0.3048)
			(end -0.120396 0.3048)
			(stroke
				(width 0.1)
				(type default)
			)
			(layer "B.Fab")
		)
		(fp_line
			(start -0.67945 -0.3048)
			(end -0.67945 0.3048)
			(stroke
				(width 0.1)
				(type default)
			)
			(layer "B.Fab")
		)
		(pad "1" smd circle
			(at 0.40005 0)
			(size 0 0)
			(layers "B.Cu" "B.Mask" "B.Paste")
			(net "P12V_HSC_GATE2")
		)
		(pad "2" smd circle
			(at -0.40005 0)
			(size 0 0)
			(layers "B.Cu" "B.Mask" "B.Paste")
			(net "HS_GATE2_R_1")
		)
	)
	(footprint ""
		(layer "B.Cu")
		(at 334.229456 -277.639272)
		(property "Reference" "PC6616"
			(at 0 0 0)
			(layer "B.SilkS")
			(hide yes)
			(effects
				(font
					(size 1.27 1.27)
				)
				(justify mirror)
			)
		)
		(property "Value" ""
			(at 0 0 0)
			(layer "B.Fab")
			(effects
				(font
					(size 1.27 1.27)
				)
				(justify mirror)
			)
		)
		(duplicate_pad_numbers_are_jumpers no)
		(fp_line
			(start -1.524 -0.762)
			(end -1.524 0.762)
			(stroke
				(width 0.1524)
				(type default)
			)
			(layer "B.SilkS")
		)
		(fp_line
			(start -1.524 0.762)
			(end 1.524 0.762)
			(stroke
				(width 0.1524)
				(type default)
			)
			(layer "B.SilkS")
		)
		(fp_line
			(start 1.524 -0.762)
			(end -1.524 -0.762)
			(stroke
				(width 0.1524)
				(type default)
			)
			(layer "B.SilkS")
		)
		(fp_line
			(start 1.524 0.762)
			(end 1.524 -0.762)
			(stroke
				(width 0.1524)
				(type default)
			)
			(layer "B.SilkS")
		)
		(fp_line
			(start -1.1049 -0.724916)
			(end 1.1049 -0.724916)
			(stroke
				(width 0.1)
				(type default)
			)
			(layer "B.Fab")
		)
		(fp_line
			(start -1.1049 0.724916)
			(end -1.1049 -0.724916)
			(stroke
				(width 0.1)
				(type default)
			)
			(layer "B.Fab")
		)
		(fp_line
			(start 1.1049 -0.724916)
			(end 1.1049 0.724916)
			(stroke
				(width 0.1)
				(type default)
			)
			(layer "B.Fab")
		)
		(fp_line
			(start 1.1049 0.724916)
			(end -1.1049 0.724916)
			(stroke
				(width 0.1)
				(type default)
			)
			(layer "B.Fab")
		)
		(pad "1" smd rect
			(at 0.889 0)
			(size 1.016 1.27)
			(layers "B.Cu" "B.Mask" "B.Paste")
			(net "SW_P12V_P0V8_PEX2_FLT")
		)
		(pad "2" smd rect
			(at -0.889 0)
			(size 1.016 1.27)
			(layers "B.Cu" "B.Mask" "B.Paste")
			(net "GND")
		)
	)
	(footprint ""
		(layer "B.Cu")
		(at 107.671616 -88.641936 90)
		(property "Reference" "C2672"
			(at 0 0 90)
			(layer "B.SilkS")
			(hide yes)
			(effects
				(font
					(size 1.27 1.27)
				)
				(justify mirror)
			)
		)
		(property "Value" ""
			(at 0 0 90)
			(layer "B.Fab")
			(effects
				(font
					(size 1.27 1.27)
				)
				(justify mirror)
			)
		)
		(duplicate_pad_numbers_are_jumpers no)
		(fp_line
			(start 0.7874 -0.4064)
			(end -0.7874 -0.4064)
			(stroke
				(width 0.1524)
				(type default)
			)
			(layer "B.SilkS")
		)
		(fp_line
			(start -0.7874 -0.4064)
			(end -0.7874 0.4064)
			(stroke
				(width 0.1524)
				(type default)
			)
			(layer "B.SilkS")
		)
		(fp_line
			(start 0.7874 0.4064)
			(end 0.7874 -0.4064)
			(stroke
				(width 0.1524)
				(type default)
			)
			(layer "B.SilkS")
		)
		(fp_line
			(start -0.7874 0.4064)
			(end 0.7874 0.4064)
			(stroke
				(width 0.1524)
				(type default)
			)
			(layer "B.SilkS")
		)
		(fp_line
			(start 0.67945 -0.305054)
			(end 0.12065 -0.305054)
			(stroke
				(width 0.1)
				(type default)
			)
			(layer "B.Fab")
		)
		(fp_line
			(start 0.12065 -0.305054)
			(end 0.12065 -0.2794)
			(stroke
				(width 0.1)
				(type default)
			)
			(layer "B.Fab")
		)
		(fp_line
			(start -0.12065 -0.3048)
			(end -0.67945 -0.3048)
			(stroke
				(width 0.1)
				(type default)
			)
			(layer "B.Fab")
		)
		(fp_line
			(start -0.67945 -0.3048)
			(end -0.67945 0.3048)
			(stroke
				(width 0.1)
				(type default)
			)
			(layer "B.Fab")
		)
		(fp_line
			(start 0.12065 -0.2794)
			(end -0.12065 -0.2794)
			(stroke
				(width 0.1)
				(type default)
			)
			(layer "B.Fab")
		)
		(fp_line
			(start -0.12065 -0.2794)
			(end -0.12065 -0.3048)
			(stroke
				(width 0.1)
				(type default)
			)
			(layer "B.Fab")
		)
		(fp_line
			(start 0.12065 0.2794)
			(end 0.12065 0.3048)
			(stroke
				(width 0.1)
				(type default)
			)
			(layer "B.Fab")
		)
		(fp_line
			(start -0.120396 0.2794)
			(end 0.12065 0.2794)
			(stroke
				(width 0.1)
				(type default)
			)
			(layer "B.Fab")
		)
		(fp_line
			(start 0.67945 0.3048)
			(end 0.67945 -0.305054)
			(stroke
				(width 0.1)
				(type default)
			)
			(layer "B.Fab")
		)
		(fp_line
			(start 0.12065 0.3048)
			(end 0.67945 0.3048)
			(stroke
				(width 0.1)
				(type default)
			)
			(layer "B.Fab")
		)
		(fp_line
			(start -0.120396 0.3048)
			(end -0.120396 0.2794)
			(stroke
				(width 0.1)
				(type default)
			)
			(layer "B.Fab")
		)
		(fp_line
			(start -0.67945 0.3048)
			(end -0.120396 0.3048)
			(stroke
				(width 0.1)
				(type default)
			)
			(layer "B.Fab")
		)
		(pad "1" smd circle
			(at 0.40005 0 270)
			(size 0 0)
			(layers "B.Cu" "B.Mask" "B.Paste")
			(net "P3V3_VDDAR_9ZXL0851_0_7")
		)
		(pad "2" smd circle
			(at -0.40005 0 270)
			(size 0 0)
			(layers "B.Cu" "B.Mask" "B.Paste")
			(net "GND")
		)
	)
)
